(kicad_pcb
	(version 20260206)
	(generator "pcbnew")
	(generator_version "10.0")
	(general
		(thickness 1.6)
		(legacy_teardrops no)
	)
	(paper "A4")
	(title_block
		(title "04192023_DAF0TMB3IC0_F0TG_MB_C_brd_V02_OCP.brd")
		(comment 1 "Grand Teton / footprints 525-531 of 8354")
	)
	(layers
		(0 "F.Cu" signal "TOP")
		(4 "In1.Cu" signal "GND")
		(6 "In2.Cu" signal "IN1")
		(8 "In3.Cu" signal "GND1")
		(10 "In4.Cu" signal "IN2")
		(12 "In5.Cu" signal "GND2")
		(14 "In6.Cu" signal "IN3")
		(16 "In7.Cu" signal "GND3")
		(18 "In8.Cu" signal "VCC")
		(20 "In9.Cu" signal "VCC1")
		(22 "In10.Cu" signal "GND4")
		(24 "In11.Cu" signal "IN4")
		(26 "In12.Cu" signal "GND5")
		(28 "In13.Cu" signal "IN5")
		(30 "In14.Cu" signal "GND6")
		(32 "In15.Cu" signal "IN6")
		(34 "In16.Cu" signal "GND7")
		(2 "B.Cu" signal "BOTTOM")
		(9 "F.Adhes" user "F.Adhesive")
		(11 "B.Adhes" user "B.Adhesive")
		(13 "F.Paste" user "Package Geometry/Pastemask Top")
		(15 "B.Paste" user "Package Geometry/Pastemask Bottom")
		(5 "F.SilkS" user "Ref Des/Silkscreen Top")
		(7 "B.SilkS" user "Ref Des/Silkscreen Bottom")
		(1 "F.Mask" user "Board Geometry/Soldermask Top")
		(3 "B.Mask" user "Board Geometry/Soldermask Bottom")
		(17 "Dwgs.User" user "User.Drawings")
		(19 "Cmts.User" user "User.Comments")
		(21 "Eco1.User" user "User.Eco1")
		(23 "Eco2.User" user "User.Eco2")
		(25 "Edge.Cuts" user "Board Geometry/Outline")
		(27 "Margin" user)
		(31 "F.CrtYd" user "Package Geometry/Place Bound Top")
		(29 "B.CrtYd" user "Package Geometry/Place Bound Bottom")
		(35 "F.Fab" user "Ref Des/Assembly Top")
		(33 "B.Fab" user "Ref Des/Assembly Bottom")
	)
	(footprint ""
		(layer "F.Cu")
		(at 465.169504 -41.105836 180)
		(property "Reference" "Q123"
			(at 1.585214 2.068068 0)
			(unlocked yes)
			(layer "F.SilkS")
			(effects
				(font
					(size 0.7874 0.5842)
					(thickness 0.1524)
				)
				(justify left)
			)
		)
		(property "Value" ""
			(at 0 0 180)
			(layer "F.Fab")
			(effects
				(font
					(size 1.27 1.27)
				)
			)
		)
		(duplicate_pad_numbers_are_jumpers no)
		(fp_line
			(start 1.332738 1.100074)
			(end -1.332738 1.100074)
			(stroke
				(width 0.1524)
				(type default)
			)
			(layer "F.SilkS")
		)
		(fp_line
			(start 1.332738 -1.100074)
			(end 1.332738 1.100074)
			(stroke
				(width 0.1524)
				(type default)
			)
			(layer "F.SilkS")
		)
		(fp_line
			(start 0.4826 -1.100074)
			(end 1.332738 -1.100074)
			(stroke
				(width 0.1524)
				(type default)
			)
			(layer "F.SilkS")
		)
		(fp_line
			(start 0 -0.541274)
			(end 0.4826 -1.100074)
			(stroke
				(width 0.1524)
				(type default)
			)
			(layer "F.SilkS")
		)
		(fp_line
			(start -0.4826 -1.100074)
			(end 0 -0.541274)
			(stroke
				(width 0.1524)
				(type default)
			)
			(layer "F.SilkS")
		)
		(fp_line
			(start -1.332738 1.100074)
			(end -1.332738 -1.100074)
			(stroke
				(width 0.1524)
				(type default)
			)
			(layer "F.SilkS")
		)
		(fp_line
			(start -1.332738 -1.100074)
			(end -0.4826 -1.100074)
			(stroke
				(width 0.1524)
				(type default)
			)
			(layer "F.SilkS")
		)
		(fp_poly
			(pts
				(xy -1.489456 -1.189482) (xy -2.23393 -1.43764) (xy -1.737614 -1.933956)
			)
			(stroke
				(width 0)
				(type default)
			)
			(fill yes)
			(layer "F.SilkS")
		)
		(fp_line
			(start 0.674878 1.100074)
			(end -0.674878 1.100074)
			(stroke
				(width 0.1)
				(type default)
			)
			(layer "F.Fab")
		)
		(fp_line
			(start 0.674878 -1.100074)
			(end 0.674878 1.100074)
			(stroke
				(width 0.1)
				(type default)
			)
			(layer "F.Fab")
		)
		(fp_line
			(start -0.674878 1.100074)
			(end -0.674878 -1.100074)
			(stroke
				(width 0.1)
				(type default)
			)
			(layer "F.Fab")
		)
		(fp_line
			(start -0.674878 -1.100074)
			(end 0.674878 -1.100074)
			(stroke
				(width 0.1)
				(type default)
			)
			(layer "F.Fab")
		)
		(fp_poly
			(pts
				(xy -2.2352 -0.298958) (xy -2.2352 -1.001014) (xy -1.533144 -0.649986)
			)
			(stroke
				(width 0)
				(type default)
			)
			(fill yes)
			(layer "F.Fab")
		)
		(pad "1" smd rect
			(at -0.94996 -0.649986 270)
			(size 0.4318 0.508)
			(layers "F.Cu" "F.Mask" "F.Paste")
			(net "GND")
		)
		(pad "2" smd rect
			(at -0.94996 0 270)
			(size 0.4318 0.508)
			(layers "F.Cu" "F.Mask" "F.Paste")
			(net "P12V_OCP_EN_1_R")
		)
		(pad "3" smd rect
			(at -0.94996 0.649986 270)
			(size 0.4318 0.508)
			(layers "F.Cu" "F.Mask" "F.Paste")
			(net "P12V_OCP_UV_1_R")
		)
		(pad "4" smd rect
			(at 0.94996 0.649986 270)
			(size 0.4318 0.508)
			(layers "F.Cu" "F.Mask" "F.Paste")
			(net "GND")
		)
		(pad "5" smd rect
			(at 0.94996 0 270)
			(size 0.4318 0.508)
			(layers "F.Cu" "F.Mask" "F.Paste")
			(net "P12V_OCP_1_EN_G")
		)
		(pad "6" smd rect
			(at 0.94996 -0.649986 270)
			(size 0.4318 0.508)
			(layers "F.Cu" "F.Mask" "F.Paste")
			(net "P12V_OCP_1_EN_G")
		)
	)
	(footprint ""
		(layer "F.Cu")
		(at 9.74471 -78.180692)
		(property "Reference" "R3135"
			(at 0 0 0)
			(layer "F.SilkS")
			(hide yes)
			(effects
				(font
					(size 1.27 1.27)
				)
			)
		)
		(property "Value" ""
			(at 0 0 0)
			(layer "F.Fab")
			(effects
				(font
					(size 1.27 1.27)
				)
			)
		)
		(duplicate_pad_numbers_are_jumpers no)
		(fp_line
			(start -0.7874 -0.4064)
			(end 0.7874 -0.4064)
			(stroke
				(width 0.1524)
				(type default)
			)
			(layer "F.SilkS")
		)
		(fp_line
			(start -0.7874 0.4064)
			(end -0.7874 -0.4064)
			(stroke
				(width 0.1524)
				(type default)
			)
			(layer "F.SilkS")
		)
		(fp_line
			(start 0.7874 -0.4064)
			(end 0.7874 0.4064)
			(stroke
				(width 0.1524)
				(type default)
			)
			(layer "F.SilkS")
		)
		(fp_line
			(start 0.7874 0.4064)
			(end -0.7874 0.4064)
			(stroke
				(width 0.1524)
				(type default)
			)
			(layer "F.SilkS")
		)
		(fp_line
			(start -0.67945 -0.305054)
			(end -0.12065 -0.305054)
			(stroke
				(width 0.1)
				(type default)
			)
			(layer "F.Fab")
		)
		(fp_line
			(start -0.67945 0.3048)
			(end -0.67945 -0.305054)
			(stroke
				(width 0.1)
				(type default)
			)
			(layer "F.Fab")
		)
		(fp_line
			(start -0.12065 -0.305054)
			(end -0.12065 -0.2794)
			(stroke
				(width 0.1)
				(type default)
			)
			(layer "F.Fab")
		)
		(fp_line
			(start -0.12065 -0.2794)
			(end 0.12065 -0.2794)
			(stroke
				(width 0.1)
				(type default)
			)
			(layer "F.Fab")
		)
		(fp_line
			(start -0.12065 0.2794)
			(end -0.12065 0.3048)
			(stroke
				(width 0.1)
				(type default)
			)
			(layer "F.Fab")
		)
		(fp_line
			(start -0.12065 0.3048)
			(end -0.67945 0.3048)
			(stroke
				(width 0.1)
				(type default)
			)
			(layer "F.Fab")
		)
		(fp_line
			(start 0.120396 0.2794)
			(end -0.12065 0.2794)
			(stroke
				(width 0.1)
				(type default)
			)
			(layer "F.Fab")
		)
		(fp_line
			(start 0.120396 0.3048)
			(end 0.120396 0.2794)
			(stroke
				(width 0.1)
				(type default)
			)
			(layer "F.Fab")
		)
		(fp_line
			(start 0.12065 -0.3048)
			(end 0.67945 -0.3048)
			(stroke
				(width 0.1)
				(type default)
			)
			(layer "F.Fab")
		)
		(fp_line
			(start 0.12065 -0.2794)
			(end 0.12065 -0.3048)
			(stroke
				(width 0.1)
				(type default)
			)
			(layer "F.Fab")
		)
		(fp_line
			(start 0.67945 -0.3048)
			(end 0.67945 0.3048)
			(stroke
				(width 0.1)
				(type default)
			)
			(layer "F.Fab")
		)
		(fp_line
			(start 0.67945 0.3048)
			(end 0.120396 0.3048)
			(stroke
				(width 0.1)
				(type default)
			)
			(layer "F.Fab")
		)
		(pad "1" smd circle
			(at -0.40005 0)
			(size 0 0)
			(layers "F.Cu" "F.Mask" "F.Paste")
			(net "P3V3_AUX")
		)
		(pad "2" smd circle
			(at 0.40005 0)
			(size 0 0)
			(layers "F.Cu" "F.Mask" "F.Paste")
			(net "OCP_V3_2_PRSNT1_R_N")
		)
	)
	(footprint ""
		(layer "F.Cu")
		(at 105.334054 -25.183592 180)
		(property "Reference" "C6090"
			(at 0 0 180)
			(layer "F.SilkS")
			(hide yes)
			(effects
				(font
					(size 1.27 1.27)
				)
			)
		)
		(property "Value" ""
			(at 0 0 180)
			(layer "F.Fab")
			(effects
				(font
					(size 1.27 1.27)
				)
			)
		)
		(duplicate_pad_numbers_are_jumpers no)
		(fp_line
			(start 0.7874 0.4064)
			(end -0.7874 0.4064)
			(stroke
				(width 0.1524)
				(type default)
			)
			(layer "F.SilkS")
		)
		(fp_line
			(start 0.7874 -0.4064)
			(end 0.7874 0.4064)
			(stroke
				(width 0.1524)
				(type default)
			)
			(layer "F.SilkS")
		)
		(fp_line
			(start -0.7874 0.4064)
			(end -0.7874 -0.4064)
			(stroke
				(width 0.1524)
				(type default)
			)
			(layer "F.SilkS")
		)
		(fp_line
			(start -0.7874 -0.4064)
			(end 0.7874 -0.4064)
			(stroke
				(width 0.1524)
				(type default)
			)
			(layer "F.SilkS")
		)
		(fp_line
			(start 0.67945 0.3048)
			(end 0.120396 0.3048)
			(stroke
				(width 0.1)
				(type default)
			)
			(layer "F.Fab")
		)
		(fp_line
			(start 0.67945 -0.3048)
			(end 0.67945 0.3048)
			(stroke
				(width 0.1)
				(type default)
			)
			(layer "F.Fab")
		)
		(fp_line
			(start 0.12065 -0.2794)
			(end 0.12065 -0.3048)
			(stroke
				(width 0.1)
				(type default)
			)
			(layer "F.Fab")
		)
		(fp_line
			(start 0.12065 -0.3048)
			(end 0.67945 -0.3048)
			(stroke
				(width 0.1)
				(type default)
			)
			(layer "F.Fab")
		)
		(fp_line
			(start 0.120396 0.3048)
			(end 0.120396 0.2794)
			(stroke
				(width 0.1)
				(type default)
			)
			(layer "F.Fab")
		)
		(fp_line
			(start 0.120396 0.2794)
			(end -0.12065 0.2794)
			(stroke
				(width 0.1)
				(type default)
			)
			(layer "F.Fab")
		)
		(fp_line
			(start -0.12065 0.3048)
			(end -0.67945 0.3048)
			(stroke
				(width 0.1)
				(type default)
			)
			(layer "F.Fab")
		)
		(fp_line
			(start -0.12065 0.2794)
			(end -0.12065 0.3048)
			(stroke
				(width 0.1)
				(type default)
			)
			(layer "F.Fab")
		)
		(fp_line
			(start -0.12065 -0.2794)
			(end 0.12065 -0.2794)
			(stroke
				(width 0.1)
				(type default)
			)
			(layer "F.Fab")
		)
		(fp_line
			(start -0.12065 -0.305054)
			(end -0.12065 -0.2794)
			(stroke
				(width 0.1)
				(type default)
			)
			(layer "F.Fab")
		)
		(fp_line
			(start -0.67945 0.3048)
			(end -0.67945 -0.305054)
			(stroke
				(width 0.1)
				(type default)
			)
			(layer "F.Fab")
		)
		(fp_line
			(start -0.67945 -0.305054)
			(end -0.12065 -0.305054)
			(stroke
				(width 0.1)
				(type default)
			)
			(layer "F.Fab")
		)
		(pad "1" smd circle
			(at -0.40005 0 180)
			(size 0 0)
			(layers "F.Cu" "F.Mask" "F.Paste")
			(net "XTAL_USB_CPU0_HUB2_XOUT")
		)
		(pad "2" smd circle
			(at 0.40005 0 180)
			(size 0 0)
			(layers "F.Cu" "F.Mask" "F.Paste")
			(net "GND")
		)
	)
	(footprint ""
		(layer "F.Cu")
		(at 169.058844 -370.57203 -90)
		(property "Reference" "C746"
			(at 0 0 270)
			(layer "F.SilkS")
			(hide yes)
			(effects
				(font
					(size 1.27 1.27)
				)
			)
		)
		(property "Value" ""
			(at 0 0 270)
			(layer "F.Fab")
			(effects
				(font
					(size 1.27 1.27)
				)
			)
		)
		(duplicate_pad_numbers_are_jumpers no)
		(fp_line
			(start -0.299974 0.150114)
			(end -0.299974 -0.150114)
			(stroke
				(width 0.1)
				(type default)
			)
			(layer "F.Fab")
		)
		(fp_line
			(start 0.299974 0.150114)
			(end -0.299974 0.150114)
			(stroke
				(width 0.1)
				(type default)
			)
			(layer "F.Fab")
		)
		(fp_line
			(start -0.299974 -0.150114)
			(end 0.299974 -0.150114)
			(stroke
				(width 0.1)
				(type default)
			)
			(layer "F.Fab")
		)
		(fp_line
			(start 0.299974 -0.150114)
			(end 0.299974 0.150114)
			(stroke
				(width 0.1)
				(type default)
			)
			(layer "F.Fab")
		)
		(pad "1" smd rect
			(at -0.2667 0 270)
			(size 0.3048 0.381)
			(layers "F.Cu" "F.Mask" "F.Paste")
			(net "P5E_CPU1_P2_TX_C_DN<13>")
		)
		(pad "2" smd rect
			(at 0.2667 0 270)
			(size 0.3048 0.381)
			(layers "F.Cu" "F.Mask" "F.Paste")
			(net "P5E_CPU1_P2_TX_DN<13>")
		)
	)
	(footprint ""
		(layer "F.Cu")
		(at 229.87 -282.188666 180)
		(property "Reference" "PC6523"
			(at 0 0 180)
			(layer "F.SilkS")
			(hide yes)
			(effects
				(font
					(size 1.27 1.27)
				)
			)
		)
		(property "Value" ""
			(at 0 0 180)
			(layer "F.Fab")
			(effects
				(font
					(size 1.27 1.27)
				)
			)
		)
		(duplicate_pad_numbers_are_jumpers no)
		(fp_line
			(start 1.524 0.762)
			(end -1.524 0.762)
			(stroke
				(width 0.1524)
				(type default)
			)
			(layer "F.SilkS")
		)
		(fp_line
			(start 1.524 -0.762)
			(end 1.524 0.762)
			(stroke
				(width 0.1524)
				(type default)
			)
			(layer "F.SilkS")
		)
		(fp_line
			(start -1.524 0.762)
			(end -1.524 -0.762)
			(stroke
				(width 0.1524)
				(type default)
			)
			(layer "F.SilkS")
		)
		(fp_line
			(start -1.524 -0.762)
			(end 1.524 -0.762)
			(stroke
				(width 0.1524)
				(type default)
			)
			(layer "F.SilkS")
		)
		(fp_line
			(start 1.1049 0.724916)
			(end 1.1049 -0.724916)
			(stroke
				(width 0.1)
				(type default)
			)
			(layer "F.Fab")
		)
		(fp_line
			(start 1.1049 -0.724916)
			(end -1.1049 -0.724916)
			(stroke
				(width 0.1)
				(type default)
			)
			(layer "F.Fab")
		)
		(fp_line
			(start -1.1049 0.724916)
			(end 1.1049 0.724916)
			(stroke
				(width 0.1)
				(type default)
			)
			(layer "F.Fab")
		)
		(fp_line
			(start -1.1049 -0.724916)
			(end -1.1049 0.724916)
			(stroke
				(width 0.1)
				(type default)
			)
			(layer "F.Fab")
		)
		(pad "1" smd rect
			(at -0.889 0)
			(size 1.016 1.27)
			(layers "F.Cu" "F.Mask" "F.Paste")
			(net "SW_P12V_AUX_P1V8_RETIMER_CPU1_FLT")
		)
		(pad "2" smd rect
			(at 0.889 0)
			(size 1.016 1.27)
			(layers "F.Cu" "F.Mask" "F.Paste")
			(net "GND")
		)
	)
	(footprint ""
		(layer "F.Cu")
		(at 80.925162 -25.358598 180)
		(property "Reference" "PR4522"
			(at 0 0 180)
			(layer "F.SilkS")
			(hide yes)
			(effects
				(font
					(size 1.27 1.27)
				)
			)
		)
		(property "Value" ""
			(at 0 0 180)
			(layer "F.Fab")
			(effects
				(font
					(size 1.27 1.27)
				)
			)
		)
		(duplicate_pad_numbers_are_jumpers no)
		(fp_line
			(start 0.7874 0.4064)
			(end -0.7874 0.4064)
			(stroke
				(width 0.1524)
				(type default)
			)
			(layer "F.SilkS")
		)
		(fp_line
			(start 0.7874 -0.4064)
			(end 0.7874 0.4064)
			(stroke
				(width 0.1524)
				(type default)
			)
			(layer "F.SilkS")
		)
		(fp_line
			(start -0.7874 0.4064)
			(end -0.7874 -0.4064)
			(stroke
				(width 0.1524)
				(type default)
			)
			(layer "F.SilkS")
		)
		(fp_line
			(start -0.7874 -0.4064)
			(end 0.7874 -0.4064)
			(stroke
				(width 0.1524)
				(type default)
			)
			(layer "F.SilkS")
		)
		(fp_line
			(start 0.67945 0.3048)
			(end 0.120396 0.3048)
			(stroke
				(width 0.1)
				(type default)
			)
			(layer "F.Fab")
		)
		(fp_line
			(start 0.67945 -0.3048)
			(end 0.67945 0.3048)
			(stroke
				(width 0.1)
				(type default)
			)
			(layer "F.Fab")
		)
		(fp_line
			(start 0.12065 -0.2794)
			(end 0.12065 -0.3048)
			(stroke
				(width 0.1)
				(type default)
			)
			(layer "F.Fab")
		)
		(fp_line
			(start 0.12065 -0.3048)
			(end 0.67945 -0.3048)
			(stroke
				(width 0.1)
				(type default)
			)
			(layer "F.Fab")
		)
		(fp_line
			(start 0.120396 0.3048)
			(end 0.120396 0.2794)
			(stroke
				(width 0.1)
				(type default)
			)
			(layer "F.Fab")
		)
		(fp_line
			(start 0.120396 0.2794)
			(end -0.12065 0.2794)
			(stroke
				(width 0.1)
				(type default)
			)
			(layer "F.Fab")
		)
		(fp_line
			(start -0.12065 0.3048)
			(end -0.67945 0.3048)
			(stroke
				(width 0.1)
				(type default)
			)
			(layer "F.Fab")
		)
		(fp_line
			(start -0.12065 0.2794)
			(end -0.12065 0.3048)
			(stroke
				(width 0.1)
				(type default)
			)
			(layer "F.Fab")
		)
		(fp_line
			(start -0.12065 -0.2794)
			(end 0.12065 -0.2794)
			(stroke
				(width 0.1)
				(type default)
			)
			(layer "F.Fab")
		)
		(fp_line
			(start -0.12065 -0.305054)
			(end -0.12065 -0.2794)
			(stroke
				(width 0.1)
				(type default)
			)
			(layer "F.Fab")
		)
		(fp_line
			(start -0.67945 0.3048)
			(end -0.67945 -0.305054)
			(stroke
				(width 0.1)
				(type default)
			)
			(layer "F.Fab")
		)
		(fp_line
			(start -0.67945 -0.305054)
			(end -0.12065 -0.305054)
			(stroke
				(width 0.1)
				(type default)
			)
			(layer "F.Fab")
		)
		(pad "1" smd circle
			(at -0.40005 0 180)
			(size 0 0)
			(layers "F.Cu" "F.Mask" "F.Paste")
			(net "P12V_OCP_V3_2")
		)
		(pad "2" smd circle
			(at 0.40005 0 180)
			(size 0 0)
			(layers "F.Cu" "F.Mask" "F.Paste")
			(net "P12V_OCP_GATE_2")
		)
	)
	(footprint ""
		(layer "F.Cu")
		(at 186.577478 -351.383854 -90)
		(property "Reference" "PC511_1"
			(at 0 0 270)
			(layer "F.SilkS")
			(hide yes)
			(effects
				(font
					(size 1.27 1.27)
				)
			)
		)
		(property "Value" ""
			(at 0 0 270)
			(layer "F.Fab")
			(effects
				(font
					(size 1.27 1.27)
				)
			)
		)
		(duplicate_pad_numbers_are_jumpers no)
		(fp_line
			(start -0.7874 0.4064)
			(end -0.7874 -0.4064)
			(stroke
				(width 0.1524)
				(type default)
			)
			(layer "F.SilkS")
		)
		(fp_line
			(start 0.7874 0.4064)
			(end -0.7874 0.4064)
			(stroke
				(width 0.1524)
				(type default)
			)
			(layer "F.SilkS")
		)
		(fp_line
			(start -0.7874 -0.4064)
			(end 0.7874 -0.4064)
			(stroke
				(width 0.1524)
				(type default)
			)
			(layer "F.SilkS")
		)
		(fp_line
			(start 0.7874 -0.4064)
			(end 0.7874 0.4064)
			(stroke
				(width 0.1524)
				(type default)
			)
			(layer "F.SilkS")
		)
		(fp_line
			(start -0.67945 0.3048)
			(end -0.67945 -0.305054)
			(stroke
				(width 0.1)
				(type default)
			)
			(layer "F.Fab")
		)
		(fp_line
			(start -0.12065 0.3048)
			(end -0.67945 0.3048)
			(stroke
				(width 0.1)
				(type default)
			)
			(layer "F.Fab")
		)
		(fp_line
			(start 0.120396 0.3048)
			(end 0.120396 0.2794)
			(stroke
				(width 0.1)
				(type default)
			)
			(layer "F.Fab")
		)
		(fp_line
			(start 0.67945 0.3048)
			(end 0.120396 0.3048)
			(stroke
				(width 0.1)
				(type default)
			)
			(layer "F.Fab")
		)
		(fp_line
			(start -0.12065 0.2794)
			(end -0.12065 0.3048)
			(stroke
				(width 0.1)
				(type default)
			)
			(layer "F.Fab")
		)
		(fp_line
			(start 0.120396 0.2794)
			(end -0.12065 0.2794)
			(stroke
				(width 0.1)
				(type default)
			)
			(layer "F.Fab")
		)
		(fp_line
			(start -0.12065 -0.2794)
			(end 0.12065 -0.2794)
			(stroke
				(width 0.1)
				(type default)
			)
			(layer "F.Fab")
		)
		(fp_line
			(start 0.12065 -0.2794)
			(end 0.12065 -0.3048)
			(stroke
				(width 0.1)
				(type default)
			)
			(layer "F.Fab")
		)
		(fp_line
			(start 0.12065 -0.3048)
			(end 0.67945 -0.3048)
			(stroke
				(width 0.1)
				(type default)
			)
			(layer "F.Fab")
		)
		(fp_line
			(start 0.67945 -0.3048)
			(end 0.67945 0.3048)
			(stroke
				(width 0.1)
				(type default)
			)
			(layer "F.Fab")
		)
		(fp_line
			(start -0.67945 -0.305054)
			(end -0.12065 -0.305054)
			(stroke
				(width 0.1)
				(type default)
			)
			(layer "F.Fab")
		)
		(fp_line
			(start -0.12065 -0.305054)
			(end -0.12065 -0.2794)
			(stroke
				(width 0.1)
				(type default)
			)
			(layer "F.Fab")
		)
		(pad "1" smd circle
			(at -0.40005 0 270)
			(size 0 0)
			(layers "F.Cu" "F.Mask" "F.Paste")
			(net "SW_P12V_AUX_PVDD11_S3_P1_FLT")
		)
		(pad "2" smd circle
			(at 0.40005 0 270)
			(size 0 0)
			(layers "F.Cu" "F.Mask" "F.Paste")
			(net "GND")
		)
	)
)
